(kicad_pcb
	(version 20260206)
	(generator "pcbnew")
	(generator_version "10.0")
	(general
		(thickness 1.6)
		(legacy_teardrops no)
	)
	(paper "A4")
	(title_block
		(title "Wiwynn_Tioga_Pass_MB.brd")
		(comment 1 "Tioga Pass / footprints 110-117 of 4770")
	)
	(layers
		(0 "F.Cu" signal "TOP")
		(4 "In1.Cu" signal "L2GND")
		(6 "In2.Cu" signal "L3")
		(8 "In3.Cu" signal "L4GND")
		(10 "In4.Cu" signal "L5")
		(12 "In5.Cu" signal "L6GND")
		(14 "In6.Cu" signal "L7VCC")
		(16 "In7.Cu" signal "L8VCC")
		(18 "In8.Cu" signal "L9GND")
		(20 "In9.Cu" signal "L10")
		(22 "In10.Cu" signal "L11GND")
		(24 "In11.Cu" signal "L12")
		(26 "In12.Cu" signal "L13GND")
		(2 "B.Cu" signal "BOTTOM")
		(9 "F.Adhes" user "F.Adhesive")
		(11 "B.Adhes" user "B.Adhesive")
		(13 "F.Paste" user "Package Geometry/Pastemask Top")
		(15 "B.Paste" user "Package Geometry/Pastemask Bottom")
		(5 "F.SilkS" user "Ref Des/Silkscreen Top")
		(7 "B.SilkS" user "Ref Des/Silkscreen Bottom")
		(1 "F.Mask" user "Board Geometry/Soldermask Top")
		(3 "B.Mask" user "Board Geometry/Soldermask Bottom")
		(17 "Dwgs.User" user "User.Drawings")
		(19 "Cmts.User" user "User.Comments")
		(21 "Eco1.User" user "User.Eco1")
		(23 "Eco2.User" user "User.Eco2")
		(25 "Edge.Cuts" user "Board Geometry/Outline")
		(27 "Margin" user)
		(31 "F.CrtYd" user "Package Geometry/Place Bound Top")
		(29 "B.CrtYd" user "Package Geometry/Place Bound Bottom")
		(35 "F.Fab" user "Ref Des/Assembly Top")
		(33 "B.Fab" user "Ref Des/Assembly Bottom")
	)
	(footprint ""
		(layer "F.Cu")
		(at 436.547006 -41.663874 180)
		(property "Reference" "R25W19"
			(at 0 0 180)
			(layer "F.SilkS")
			(hide yes)
			(effects
				(font
					(size 1.27 1.27)
				)
			)
		)
		(property "Value" "*"
			(at 0.064008 -4.108196 180)
			(unlocked yes)
			(layer "F.Fab")
			(hide yes)
			(effects
				(font
					(size 1.27 1.016)
					(thickness 0.1524)
				)
			)
		)
		(property "Device Type" "120R2F-GP_RCL_GP-120R2F-GP,64.A"
			(at 0.064008 -5.632196 180)
			(unlocked yes)
			(layer "F.Fab")
			(hide yes)
			(effects
				(font
					(size 1.27 1.016)
					(thickness 0.1524)
				)
			)
		)
		(duplicate_pad_numbers_are_jumpers no)
		(fp_line
			(start 0.508 -0.9398)
			(end -0.508 -0.9398)
			(stroke
				(width 0.1524)
				(type default)
			)
			(layer "F.SilkS")
		)
		(fp_line
			(start -0.508 -0.9398)
			(end -0.508 0.9398)
			(stroke
				(width 0.1524)
				(type default)
			)
			(layer "F.SilkS")
		)
		(fp_rect
			(start -0.508 0.9398)
			(end 0.508 -0.9398)
			(stroke
				(width 0)
				(type default)
			)
			(fill no)
			(layer "F.CrtYd")
		)
		(fp_rect
			(start -0.508 0.9398)
			(end 0.508 -0.9398)
			(stroke
				(width 0)
				(type default)
			)
			(fill no)
			(layer "F.Fab")
		)
		(pad "1" smd custom
			(at 0 -0.4445 180)
			(size 0.1397 0.1397)
			(layers "F.Cu" "F.Mask" "F.Paste")
			(net "GND")
			(options
				(clearance outline)
				(anchor circle)
			)
			(primitives
				(gr_poly
					(pts
						(arc
							(start -0.1778 -0.2794)
							(mid -0.249642 -0.249642)
							(end -0.2794 -0.1778)
						)
						(arc
							(start -0.2794 0.1778)
							(mid -0.249642 0.249642)
							(end -0.1778 0.2794)
						)
						(arc
							(start 0.1778 0.2794)
							(mid 0.249642 0.249642)
							(end 0.2794 0.1778)
						)
						(arc
							(start 0.2794 -0.1778)
							(mid 0.249642 -0.249642)
							(end 0.1778 -0.2794)
						)
					)
					(width 0)
					(fill yes)
				)
			)
		)
		(pad "2" smd custom
			(at 0 0.4445 180)
			(size 0.1397 0.1397)
			(layers "F.Cu" "F.Mask" "F.Paste")
			(net "BMC_M_A7")
			(options
				(clearance outline)
				(anchor circle)
			)
			(primitives
				(gr_poly
					(pts
						(arc
							(start -0.1778 -0.2794)
							(mid -0.249642 -0.249642)
							(end -0.2794 -0.1778)
						)
						(arc
							(start -0.2794 0.1778)
							(mid -0.249642 0.249642)
							(end -0.1778 0.2794)
						)
						(arc
							(start 0.1778 0.2794)
							(mid 0.249642 0.249642)
							(end 0.2794 0.1778)
						)
						(arc
							(start 0.2794 -0.1778)
							(mid 0.249642 -0.249642)
							(end 0.1778 -0.2794)
						)
					)
					(width 0)
					(fill yes)
				)
			)
		)
	)
	(footprint ""
		(layer "F.Cu")
		(at 383.345182 -75.137518 90)
		(property "Reference" "R7E2"
			(at 0 0 90)
			(layer "F.SilkS")
			(hide yes)
			(effects
				(font
					(size 1.27 1.27)
				)
			)
		)
		(property "Value" ""
			(at 0 0 90)
			(layer "F.Fab")
			(effects
				(font
					(size 1.27 1.27)
				)
			)
		)
		(duplicate_pad_numbers_are_jumpers no)
		(fp_poly
			(pts
				(xy -0.2794 -0.1016) (xy 0.2794 -0.1016) (xy 0.2794 0.9906) (xy -0.2794 0.9906)
			)
			(stroke
				(width 0)
				(type default)
			)
			(fill no)
			(layer "F.CrtYd")
		)
		(fp_line
			(start 0.2794 -0.1016)
			(end -0.2794 -0.1016)
			(stroke
				(width 0.1)
				(type default)
			)
			(layer "F.Fab")
		)
		(fp_line
			(start -0.2794 -0.1016)
			(end -0.2794 0.9906)
			(stroke
				(width 0.1)
				(type default)
			)
			(layer "F.Fab")
		)
		(fp_line
			(start 0.2794 0.9906)
			(end 0.2794 -0.1016)
			(stroke
				(width 0.1)
				(type default)
			)
			(layer "F.Fab")
		)
		(fp_line
			(start -0.2794 0.9906)
			(end 0.2794 0.9906)
			(stroke
				(width 0.1)
				(type default)
			)
			(layer "F.Fab")
		)
		(pad "1" smd rect
			(at 0 0 90)
			(size 0.508 0.508)
			(layers "F.Cu" "F.Mask" "F.Paste")
			(net "PVCCIO_CPU0")
		)
		(pad "2" smd rect
			(at 0 0.889 90)
			(size 0.508 0.508)
			(layers "F.Cu" "F.Mask" "F.Paste")
			(net "H_CPU0_THERMTRIP_G_N")
		)
		(zone
			(layer "F.Cu")
			(hatch none 0.5)
			(connect_pads
				(clearance 0)
			)
			(min_thickness 0.25)
			(keepout
				(tracks allowed)
				(vias not_allowed)
				(pads allowed)
				(copperpour not_allowed)
				(footprints allowed)
			)
			(placement
				(enabled no)
				(sheetname "")
			)
			(fill
				(thermal_gap 0.5)
				(thermal_bridge_width 0.5)
				(island_removal_mode 0)
			)
			(polygon
				(pts
					(xy 383.599182 -74.883518) (xy 383.599182 -75.391518) (xy 383.980182 -75.391518) (xy 383.980182 -74.883518)
				)
			)
		)
		(zone
			(layer "F.Cu")
			(hatch none 0.5)
			(connect_pads
				(clearance 0)
			)
			(min_thickness 0.25)
			(keepout
				(tracks not_allowed)
				(vias allowed)
				(pads allowed)
				(copperpour not_allowed)
				(footprints allowed)
			)
			(placement
				(enabled no)
				(sheetname "")
			)
			(fill
				(thermal_gap 0.5)
				(thermal_bridge_width 0.5)
				(island_removal_mode 0)
			)
			(polygon
				(pts
					(xy 383.980182 -74.883518) (xy 383.980182 -75.391518) (xy 383.599182 -75.391518) (xy 383.599182 -74.883518)
				)
			)
		)
	)
	(footprint ""
		(layer "F.Cu")
		(at 268.50721 -84.890102)
		(property "Reference" "C5D1"
			(at 0 0 0)
			(layer "F.SilkS")
			(hide yes)
			(effects
				(font
					(size 1.27 1.27)
				)
			)
		)
		(property "Value" ""
			(at 0 0 0)
			(layer "F.Fab")
			(effects
				(font
					(size 1.27 1.27)
				)
			)
		)
		(duplicate_pad_numbers_are_jumpers no)
		(fp_poly
			(pts
				(xy -0.4953 -0.2032) (xy 0.4953 -0.2032) (xy 0.4953 1.6002) (xy -0.4953 1.6002)
			)
			(stroke
				(width 0)
				(type default)
			)
			(fill no)
			(layer "F.CrtYd")
		)
		(fp_line
			(start -0.4953 -0.2032)
			(end 0.4953 -0.2032)
			(stroke
				(width 0.1)
				(type default)
			)
			(layer "F.Fab")
		)
		(fp_line
			(start -0.4953 1.6002)
			(end -0.4953 -0.2032)
			(stroke
				(width 0.1)
				(type default)
			)
			(layer "F.Fab")
		)
		(fp_line
			(start 0.4953 -0.2032)
			(end 0.4953 1.6002)
			(stroke
				(width 0.1)
				(type default)
			)
			(layer "F.Fab")
		)
		(fp_line
			(start 0.4953 1.6002)
			(end -0.4953 1.6002)
			(stroke
				(width 0.1)
				(type default)
			)
			(layer "F.Fab")
		)
		(pad "1" smd rect
			(at 0 0)
			(size 0.762 0.889)
			(layers "F.Cu" "F.Mask" "F.Paste")
			(net "PVDDQ_DEF")
		)
		(pad "2" smd rect
			(at 0 1.397)
			(size 0.762 0.889)
			(layers "F.Cu" "F.Mask" "F.Paste")
			(net "GND")
		)
		(zone
			(layer "F.Cu")
			(hatch none 0.5)
			(connect_pads
				(clearance 0)
			)
			(min_thickness 0.25)
			(keepout
				(tracks not_allowed)
				(vias allowed)
				(pads allowed)
				(copperpour not_allowed)
				(footprints allowed)
			)
			(placement
				(enabled no)
				(sheetname "")
			)
			(fill
				(thermal_gap 0.5)
				(thermal_bridge_width 0.5)
				(island_removal_mode 0)
			)
			(polygon
				(pts
					(xy 268.12621 -84.445602) (xy 268.88821 -84.445602) (xy 268.88821 -83.937602) (xy 268.12621 -83.937602)
				)
			)
		)
	)
	(footprint ""
		(layer "F.Cu")
		(at 403.988016 -152.703784 90)
		(property "Reference" "C8A4"
			(at 0 0 90)
			(layer "F.SilkS")
			(hide yes)
			(effects
				(font
					(size 1.27 1.27)
				)
			)
		)
		(property "Value" ""
			(at 0 0 90)
			(layer "F.Fab")
			(effects
				(font
					(size 1.27 1.27)
				)
			)
		)
		(duplicate_pad_numbers_are_jumpers no)
		(fp_poly
			(pts
				(xy -0.4953 -0.2032) (xy 0.4953 -0.2032) (xy 0.4953 1.6002) (xy -0.4953 1.6002)
			)
			(stroke
				(width 0)
				(type default)
			)
			(fill no)
			(layer "F.CrtYd")
		)
		(fp_line
			(start 0.4953 -0.2032)
			(end 0.4953 1.6002)
			(stroke
				(width 0.1)
				(type default)
			)
			(layer "F.Fab")
		)
		(fp_line
			(start -0.4953 -0.2032)
			(end 0.4953 -0.2032)
			(stroke
				(width 0.1)
				(type default)
			)
			(layer "F.Fab")
		)
		(fp_line
			(start 0.4953 1.6002)
			(end -0.4953 1.6002)
			(stroke
				(width 0.1)
				(type default)
			)
			(layer "F.Fab")
		)
		(fp_line
			(start -0.4953 1.6002)
			(end -0.4953 -0.2032)
			(stroke
				(width 0.1)
				(type default)
			)
			(layer "F.Fab")
		)
		(pad "1" smd rect
			(at 0 0 90)
			(size 0.762 0.889)
			(layers "F.Cu" "F.Mask" "F.Paste")
			(net "P3V3_STBY")
		)
		(pad "2" smd rect
			(at 0 1.397 90)
			(size 0.762 0.889)
			(layers "F.Cu" "F.Mask" "F.Paste")
			(net "GND")
		)
		(zone
			(layer "F.Cu")
			(hatch none 0.5)
			(connect_pads
				(clearance 0)
			)
			(min_thickness 0.25)
			(keepout
				(tracks not_allowed)
				(vias allowed)
				(pads allowed)
				(copperpour not_allowed)
				(footprints allowed)
			)
			(placement
				(enabled no)
				(sheetname "")
			)
			(fill
				(thermal_gap 0.5)
				(thermal_bridge_width 0.5)
				(island_removal_mode 0)
			)
			(polygon
				(pts
					(xy 404.432516 -152.322784) (xy 404.432516 -153.084784) (xy 404.940516 -153.084784) (xy 404.940516 -152.322784)
				)
			)
		)
	)
	(footprint ""
		(layer "F.Cu")
		(at 184.985914 -61.976 180)
		(property "Reference" "R4E20"
			(at 0 0 180)
			(layer "F.SilkS")
			(hide yes)
			(effects
				(font
					(size 1.27 1.27)
				)
			)
		)
		(property "Value" ""
			(at 0 0 180)
			(layer "F.Fab")
			(effects
				(font
					(size 1.27 1.27)
				)
			)
		)
		(duplicate_pad_numbers_are_jumpers no)
		(fp_rect
			(start 0.2794 -0.1016)
			(end -0.2794 0.9906)
			(stroke
				(width 0)
				(type default)
			)
			(fill no)
			(layer "F.CrtYd")
		)
		(fp_line
			(start 0.2794 0.9906)
			(end 0.2794 -0.1016)
			(stroke
				(width 0.1)
				(type default)
			)
			(layer "F.Fab")
		)
		(fp_line
			(start 0.2794 -0.1016)
			(end -0.2794 -0.1016)
			(stroke
				(width 0.1)
				(type default)
			)
			(layer "F.Fab")
		)
		(fp_line
			(start -0.2794 0.9906)
			(end 0.2794 0.9906)
			(stroke
				(width 0.1)
				(type default)
			)
			(layer "F.Fab")
		)
		(fp_line
			(start -0.2794 -0.1016)
			(end -0.2794 0.9906)
			(stroke
				(width 0.1)
				(type default)
			)
			(layer "F.Fab")
		)
		(pad "1" smd rect
			(at 0 0 180)
			(size 0.508 0.508)
			(layers "F.Cu" "F.Mask" "F.Paste")
			(net "P3V3_STBY")
		)
		(pad "2" smd rect
			(at 0 0.889 180)
			(size 0.508 0.508)
			(layers "F.Cu" "F.Mask" "F.Paste")
			(net "PU_VR_PVCCIN_CPU0_FLT1_SMBALT_N")
		)
		(zone
			(layer "F.Cu")
			(hatch none 0.5)
			(connect_pads
				(clearance 0)
			)
			(min_thickness 0.25)
			(keepout
				(tracks not_allowed)
				(vias allowed)
				(pads allowed)
				(copperpour not_allowed)
				(footprints allowed)
			)
			(placement
				(enabled no)
				(sheetname "")
			)
			(fill
				(thermal_gap 0.5)
				(thermal_bridge_width 0.5)
				(island_removal_mode 0)
			)
			(polygon
				(pts
					(xy 184.731914 -62.23) (xy 185.239914 -62.23) (xy 185.239914 -62.611) (xy 184.731914 -62.611)
				)
			)
		)
		(zone
			(layer "F.Cu")
			(hatch none 0.5)
			(connect_pads
				(clearance 0)
			)
			(min_thickness 0.25)
			(keepout
				(tracks allowed)
				(vias not_allowed)
				(pads allowed)
				(copperpour not_allowed)
				(footprints allowed)
			)
			(placement
				(enabled no)
				(sheetname "")
			)
			(fill
				(thermal_gap 0.5)
				(thermal_bridge_width 0.5)
				(island_removal_mode 0)
			)
			(polygon
				(pts
					(xy 184.731914 -62.23) (xy 185.239914 -62.23) (xy 185.239914 -62.611) (xy 184.731914 -62.611)
				)
			)
		)
	)
	(footprint ""
		(layer "F.Cu")
		(at 193.929 -67.1576 90)
		(property "Reference" "C4D50"
			(at 0 0 90)
			(layer "F.SilkS")
			(hide yes)
			(effects
				(font
					(size 1.27 1.27)
				)
			)
		)
		(property "Value" ""
			(at 0 0 90)
			(layer "F.Fab")
			(effects
				(font
					(size 1.27 1.27)
				)
			)
		)
		(duplicate_pad_numbers_are_jumpers no)
		(fp_rect
			(start -0.3048 0.9906)
			(end 0.3048 -0.1016)
			(stroke
				(width 0)
				(type default)
			)
			(fill no)
			(layer "F.CrtYd")
		)
		(fp_line
			(start 0.3048 -0.1016)
			(end -0.3048 -0.1016)
			(stroke
				(width 0.1)
				(type default)
			)
			(layer "F.Fab")
		)
		(fp_line
			(start -0.3048 -0.1016)
			(end -0.3048 0.9906)
			(stroke
				(width 0.1)
				(type default)
			)
			(layer "F.Fab")
		)
		(fp_line
			(start 0.3048 0.9906)
			(end 0.3048 -0.1016)
			(stroke
				(width 0.1)
				(type default)
			)
			(layer "F.Fab")
		)
		(fp_line
			(start -0.3048 0.9906)
			(end 0.3048 0.9906)
			(stroke
				(width 0.1)
				(type default)
			)
			(layer "F.Fab")
		)
		(pad "1" smd rect
			(at 0 0 90)
			(size 0.508 0.508)
			(layers "F.Cu" "F.Mask" "F.Paste")
			(net "VR_PVCCIN_CPU0_PH2_BOOT")
		)
		(pad "2" smd rect
			(at 0 0.889 90)
			(size 0.508 0.508)
			(layers "F.Cu" "F.Mask" "F.Paste")
			(net "VR_PVCCIN_CPU0_PH2_PHASE")
		)
		(zone
			(layer "F.Cu")
			(hatch none 0.5)
			(connect_pads
				(clearance 0)
			)
			(min_thickness 0.25)
			(keepout
				(tracks not_allowed)
				(vias allowed)
				(pads allowed)
				(copperpour not_allowed)
				(footprints allowed)
			)
			(placement
				(enabled no)
				(sheetname "")
			)
			(fill
				(thermal_gap 0.5)
				(thermal_bridge_width 0.5)
				(island_removal_mode 0)
			)
			(polygon
				(pts
					(xy 194.564 -66.9036) (xy 194.564 -67.4116) (xy 194.183 -67.4116) (xy 194.183 -66.9036)
				)
			)
		)
		(zone
			(layer "F.Cu")
			(hatch none 0.5)
			(connect_pads
				(clearance 0)
			)
			(min_thickness 0.25)
			(keepout
				(tracks allowed)
				(vias not_allowed)
				(pads allowed)
				(copperpour not_allowed)
				(footprints allowed)
			)
			(placement
				(enabled no)
				(sheetname "")
			)
			(fill
				(thermal_gap 0.5)
				(thermal_bridge_width 0.5)
				(island_removal_mode 0)
			)
			(polygon
				(pts
					(xy 194.564 -66.9036) (xy 194.564 -67.4116) (xy 194.183 -67.4116) (xy 194.183 -66.9036)
				)
			)
		)
	)
	(footprint ""
		(layer "F.Cu")
		(at 402.717 -24.892)
		(property "Reference" "R25W113"
			(at -0.8382 -0.67818 0)
			(unlocked yes)
			(layer "F.SilkS")
			(effects
				(font
					(size 0.4064 0.254)
					(thickness 0.1524)
				)
				(justify left)
			)
		)
		(property "Value" ""
			(at 0 0 0)
			(layer "F.Fab")
			(effects
				(font
					(size 1.27 1.27)
				)
			)
		)
		(duplicate_pad_numbers_are_jumpers no)
		(fp_poly
			(pts
				(xy -0.2794 -0.1016) (xy 0.2794 -0.1016) (xy 0.2794 0.9906) (xy -0.2794 0.9906)
			)
			(stroke
				(width 0)
				(type default)
			)
			(fill no)
			(layer "F.CrtYd")
		)
		(fp_line
			(start -0.2794 -0.1016)
			(end -0.2794 0.9906)
			(stroke
				(width 0.1)
				(type default)
			)
			(layer "F.Fab")
		)
		(fp_line
			(start -0.2794 0.9906)
			(end 0.2794 0.9906)
			(stroke
				(width 0.1)
				(type default)
			)
			(layer "F.Fab")
		)
		(fp_line
			(start 0.2794 -0.1016)
			(end -0.2794 -0.1016)
			(stroke
				(width 0.1)
				(type default)
			)
			(layer "F.Fab")
		)
		(fp_line
			(start 0.2794 0.9906)
			(end 0.2794 -0.1016)
			(stroke
				(width 0.1)
				(type default)
			)
			(layer "F.Fab")
		)
		(pad "1" smd rect
			(at 0 0)
			(size 0.508 0.508)
			(layers "F.Cu" "F.Mask" "F.Paste")
			(net "P3V3_STBY")
		)
		(pad "2" smd rect
			(at 0 0.889)
			(size 0.508 0.508)
			(layers "F.Cu" "F.Mask" "F.Paste")
			(net "RMII_BMC_PCH_SPRNGVLLE_TXD1_R")
		)
		(zone
			(layer "F.Cu")
			(hatch none 0.5)
			(connect_pads
				(clearance 0)
			)
			(min_thickness 0.25)
			(keepout
				(tracks allowed)
				(vias not_allowed)
				(pads allowed)
				(copperpour not_allowed)
				(footprints allowed)
			)
			(placement
				(enabled no)
				(sheetname "")
			)
			(fill
				(thermal_gap 0.5)
				(thermal_bridge_width 0.5)
				(island_removal_mode 0)
			)
			(polygon
				(pts
					(xy 402.463 -24.638) (xy 402.971 -24.638) (xy 402.971 -24.257) (xy 402.463 -24.257)
				)
			)
		)
		(zone
			(layer "F.Cu")
			(hatch none 0.5)
			(connect_pads
				(clearance 0)
			)
			(min_thickness 0.25)
			(keepout
				(tracks not_allowed)
				(vias allowed)
				(pads allowed)
				(copperpour not_allowed)
				(footprints allowed)
			)
			(placement
				(enabled no)
				(sheetname "")
			)
			(fill
				(thermal_gap 0.5)
				(thermal_bridge_width 0.5)
				(island_removal_mode 0)
			)
			(polygon
				(pts
					(xy 402.463 -24.257) (xy 402.971 -24.257) (xy 402.971 -24.638) (xy 402.463 -24.638)
				)
			)
		)
	)
	(footprint ""
		(layer "F.Cu")
		(at 451.85838 -37.1475 90)
		(property "Reference" "R25W46"
			(at 0 0 90)
			(layer "F.SilkS")
			(hide yes)
			(effects
				(font
					(size 1.27 1.27)
				)
			)
		)
		(property "Value" "*"
			(at 0.064008 -4.108196 90)
			(unlocked yes)
			(layer "F.Fab")
			(hide yes)
			(effects
				(font
					(size 1.27 1.016)
					(thickness 0.1524)
				)
			)
		)
		(property "Device Type" "120R2F-GP_RCL_GP-120R2F-GP,64.A"
			(at 0.064008 -5.632196 90)
			(unlocked yes)
			(layer "F.Fab")
			(hide yes)
			(effects
				(font
					(size 1.27 1.016)
					(thickness 0.1524)
				)
			)
		)
		(duplicate_pad_numbers_are_jumpers no)
		(fp_line
			(start 0.508 -0.9398)
			(end -0.508 -0.9398)
			(stroke
				(width 0.1524)
				(type default)
			)
			(layer "F.SilkS")
		)
		(fp_line
			(start -0.508 -0.9398)
			(end -0.508 0.9398)
			(stroke
				(width 0.1524)
				(type default)
			)
			(layer "F.SilkS")
		)
		(fp_rect
			(start -0.508 0.9398)
			(end 0.508 -0.9398)
			(stroke
				(width 0)
				(type default)
			)
			(fill no)
			(layer "F.CrtYd")
		)
		(fp_rect
			(start -0.508 0.9398)
			(end 0.508 -0.9398)
			(stroke
				(width 0)
				(type default)
			)
			(fill no)
			(layer "F.Fab")
		)
		(pad "1" smd custom
			(at 0 -0.4445 90)
			(size 0.1397 0.1397)
			(layers "F.Cu" "F.Mask" "F.Paste")
			(net "BMC_M_A8")
			(options
				(clearance outline)
				(anchor circle)
			)
			(primitives
				(gr_poly
					(pts
						(arc
							(start -0.1778 -0.2794)
							(mid -0.249642 -0.249642)
							(end -0.2794 -0.1778)
						)
						(arc
							(start -0.2794 0.1778)
							(mid -0.249642 0.249642)
							(end -0.1778 0.2794)
						)
						(arc
							(start 0.1778 0.2794)
							(mid 0.249642 0.249642)
							(end 0.2794 0.1778)
						)
						(arc
							(start 0.2794 -0.1778)
							(mid 0.249642 -0.249642)
							(end 0.1778 -0.2794)
						)
					)
					(width 0)
					(fill yes)
				)
			)
		)
		(pad "2" smd custom
			(at 0 0.4445 90)
			(size 0.1397 0.1397)
			(layers "F.Cu" "F.Mask" "F.Paste")
			(net "P1V2_AUX_BMC")
			(options
				(clearance outline)
				(anchor circle)
			)
			(primitives
				(gr_poly
					(pts
						(arc
							(start -0.1778 -0.2794)
							(mid -0.249642 -0.249642)
							(end -0.2794 -0.1778)
						)
						(arc
							(start -0.2794 0.1778)
							(mid -0.249642 0.249642)
							(end -0.1778 0.2794)
						)
						(arc
							(start 0.1778 0.2794)
							(mid 0.249642 0.249642)
							(end 0.2794 0.1778)
						)
						(arc
							(start 0.2794 -0.1778)
							(mid 0.249642 -0.249642)
							(end 0.1778 -0.2794)
						)
					)
					(width 0)
					(fill yes)
				)
			)
		)
	)
)
